# T6G (Grand Teton) — schematic netlist excerpt (pin names and nets, part order shuffled) for the footprints in the layout excerpt that follows; sources: Cadence DE-HDL packaged netlist, KiCad conversion of 04192023_DAF0TMB3IC0_F0TG_MB_C_brd_V02_OCP.brd

C887  Q_CAP_DIFFBUS  DIFF BUS_0.22UF 6.3V 20% X6S  pkg C0201  page 64 : \1\ = P5E_CPU0_P3_TX_C_DP<7> ; \2\ = P5E_CPU0_P3_TX_DP<7>
R118  Q_RES  0 5% CHIP  pkg 0402LF  page 207 : A = SMB_SCM_2_R6_SCL ; B = PVDD11_S3_P0_PMSCL_R
R2707  Q_RES  0 5% CHIP  pkg 0402LF  page 248 : A = SMB_BMC_SWB_EN ; B = SMB_BMC_SWB_EN_R

(kicad_pcb
	(version 20260206)
	(generator "pcbnew")
	(generator_version "10.0")
	(general
		(thickness 1.6)
		(legacy_teardrops no)
	)
	(paper "A4")
	(title_block
		(title "04192023_DAF0TMB3IC0_F0TG_MB_C_brd_V02_OCP.brd")
		(comment 1 "Grand Teton / footprints 1902-1904 of 8354")
	)
	(layers
		(0 "F.Cu" signal "TOP")
		(4 "In1.Cu" signal "GND")
		(6 "In2.Cu" signal "IN1")
		(8 "In3.Cu" signal "GND1")
		(10 "In4.Cu" signal "IN2")
		(12 "In5.Cu" signal "GND2")
		(14 "In6.Cu" signal "IN3")
		(16 "In7.Cu" signal "GND3")
		(18 "In8.Cu" signal "VCC")
		(20 "In9.Cu" signal "VCC1")
		(22 "In10.Cu" signal "GND4")
		(24 "In11.Cu" signal "IN4")
		(26 "In12.Cu" signal "GND5")
		(28 "In13.Cu" signal "IN5")
		(30 "In14.Cu" signal "GND6")
		(32 "In15.Cu" signal "IN6")
		(34 "In16.Cu" signal "GND7")
		(2 "B.Cu" signal "BOTTOM")
		(9 "F.Adhes" user "F.Adhesive")
		(11 "B.Adhes" user "B.Adhesive")
		(13 "F.Paste" user "Package Geometry/Pastemask Top")
		(15 "B.Paste" user "Package Geometry/Pastemask Bottom")
		(5 "F.SilkS" user "Ref Des/Silkscreen Top")
		(7 "B.SilkS" user "Ref Des/Silkscreen Bottom")
		(1 "F.Mask" user "Board Geometry/Soldermask Top")
		(3 "B.Mask" user "Board Geometry/Soldermask Bottom")
		(17 "Dwgs.User" user "User.Drawings")
		(19 "Cmts.User" user "User.Comments")
		(21 "Eco1.User" user "User.Eco1")
		(23 "Eco2.User" user "User.Eco2")
		(25 "Edge.Cuts" user "Board Geometry/Outline")
		(27 "Margin" user)
		(31 "F.CrtYd" user "Package Geometry/Place Bound Top")
		(29 "B.CrtYd" user "Package Geometry/Place Bound Bottom")
		(35 "F.Fab" user "Ref Des/Assembly Top")
		(33 "B.Fab" user "Ref Des/Assembly Bottom")
	)
	(footprint ""
		(layer "F.Cu")
		(at 416.856418 -366.325912)
		(property "Reference" "R118"
			(at 0 0 0)
			(layer "F.SilkS")
			(hide yes)
			(effects
				(font
					(size 1.27 1.27)
				)
			)
		)
		(property "Value" ""
			(at 0 0 0)
			(layer "F.Fab")
			(effects
				(font
					(size 1.27 1.27)
				)
			)
		)
		(duplicate_pad_numbers_are_jumpers no)
		(fp_line
			(start -0.7874 -0.4064)
			(end 0.7874 -0.4064)
			(stroke
				(width 0.1524)
				(type default)
			)
			(layer "F.SilkS")
		)
		(fp_line
			(start -0.7874 0.4064)
			(end -0.7874 -0.4064)
			(stroke
				(width 0.1524)
				(type default)
			)
			(layer "F.SilkS")
		)
		(fp_line
			(start 0.7874 -0.4064)
			(end 0.7874 0.4064)
			(stroke
				(width 0.1524)
				(type default)
			)
			(layer "F.SilkS")
		)
		(fp_line
			(start 0.7874 0.4064)
			(end -0.7874 0.4064)
			(stroke
				(width 0.1524)
				(type default)
			)
			(layer "F.SilkS")
		)
		(fp_line
			(start -0.67945 -0.305054)
			(end -0.12065 -0.305054)
			(stroke
				(width 0.1)
				(type default)
			)
			(layer "F.Fab")
		)
		(fp_line
			(start -0.67945 0.3048)
			(end -0.67945 -0.305054)
			(stroke
				(width 0.1)
				(type default)
			)
			(layer "F.Fab")
		)
		(fp_line
			(start -0.12065 -0.305054)
			(end -0.12065 -0.2794)
			(stroke
				(width 0.1)
				(type default)
			)
			(layer "F.Fab")
		)
		(fp_line
			(start -0.12065 -0.2794)
			(end 0.12065 -0.2794)
			(stroke
				(width 0.1)
				(type default)
			)
			(layer "F.Fab")
		)
		(fp_line
			(start -0.12065 0.2794)
			(end -0.12065 0.3048)
			(stroke
				(width 0.1)
				(type default)
			)
			(layer "F.Fab")
		)
		(fp_line
			(start -0.12065 0.3048)
			(end -0.67945 0.3048)
			(stroke
				(width 0.1)
				(type default)
			)
			(layer "F.Fab")
		)
		(fp_line
			(start 0.120396 0.2794)
			(end -0.12065 0.2794)
			(stroke
				(width 0.1)
				(type default)
			)
			(layer "F.Fab")
		)
		(fp_line
			(start 0.120396 0.3048)
			(end 0.120396 0.2794)
			(stroke
				(width 0.1)
				(type default)
			)
			(layer "F.Fab")
		)
		(fp_line
			(start 0.12065 -0.3048)
			(end 0.67945 -0.3048)
			(stroke
				(width 0.1)
				(type default)
			)
			(layer "F.Fab")
		)
		(fp_line
			(start 0.12065 -0.2794)
			(end 0.12065 -0.3048)
			(stroke
				(width 0.1)
				(type default)
			)
			(layer "F.Fab")
		)
		(fp_line
			(start 0.67945 -0.3048)
			(end 0.67945 0.3048)
			(stroke
				(width 0.1)
				(type default)
			)
			(layer "F.Fab")
		)
		(fp_line
			(start 0.67945 0.3048)
			(end 0.120396 0.3048)
			(stroke
				(width 0.1)
				(type default)
			)
			(layer "F.Fab")
		)
		(pad "1" smd circle
			(at -0.40005 0)
			(size 0 0)
			(layers "F.Cu" "F.Mask" "F.Paste")
			(net "SMB_SCM_2_R6_SCL")
		)
		(pad "2" smd circle
			(at 0.40005 0)
			(size 0 0)
			(layers "F.Cu" "F.Mask" "F.Paste")
			(net "PVDD11_S3_P0_PMSCL_R")
		)
	)
	(footprint ""
		(layer "F.Cu")
		(at 166.3192 -432.4096 180)
		(property "Reference" "R2707"
			(at 0 0 180)
			(layer "F.SilkS")
			(hide yes)
			(effects
				(font
					(size 1.27 1.27)
				)
			)
		)
		(property "Value" ""
			(at 0 0 180)
			(layer "F.Fab")
			(effects
				(font
					(size 1.27 1.27)
				)
			)
		)
		(duplicate_pad_numbers_are_jumpers no)
		(fp_line
			(start 0.7874 0.4064)
			(end -0.7874 0.4064)
			(stroke
				(width 0.1524)
				(type default)
			)
			(layer "F.SilkS")
		)
		(fp_line
			(start 0.7874 -0.4064)
			(end 0.7874 0.4064)
			(stroke
				(width 0.1524)
				(type default)
			)
			(layer "F.SilkS")
		)
		(fp_line
			(start -0.7874 0.4064)
			(end -0.7874 -0.4064)
			(stroke
				(width 0.1524)
				(type default)
			)
			(layer "F.SilkS")
		)
		(fp_line
			(start -0.7874 -0.4064)
			(end 0.7874 -0.4064)
			(stroke
				(width 0.1524)
				(type default)
			)
			(layer "F.SilkS")
		)
		(fp_line
			(start 0.67945 0.3048)
			(end 0.120396 0.3048)
			(stroke
				(width 0.1)
				(type default)
			)
			(layer "F.Fab")
		)
		(fp_line
			(start 0.67945 -0.3048)
			(end 0.67945 0.3048)
			(stroke
				(width 0.1)
				(type default)
			)
			(layer "F.Fab")
		)
		(fp_line
			(start 0.12065 -0.2794)
			(end 0.12065 -0.3048)
			(stroke
				(width 0.1)
				(type default)
			)
			(layer "F.Fab")
		)
		(fp_line
			(start 0.12065 -0.3048)
			(end 0.67945 -0.3048)
			(stroke
				(width 0.1)
				(type default)
			)
			(layer "F.Fab")
		)
		(fp_line
			(start 0.120396 0.3048)
			(end 0.120396 0.2794)
			(stroke
				(width 0.1)
				(type default)
			)
			(layer "F.Fab")
		)
		(fp_line
			(start 0.120396 0.2794)
			(end -0.12065 0.2794)
			(stroke
				(width 0.1)
				(type default)
			)
			(layer "F.Fab")
		)
		(fp_line
			(start -0.12065 0.3048)
			(end -0.67945 0.3048)
			(stroke
				(width 0.1)
				(type default)
			)
			(layer "F.Fab")
		)
		(fp_line
			(start -0.12065 0.2794)
			(end -0.12065 0.3048)
			(stroke
				(width 0.1)
				(type default)
			)
			(layer "F.Fab")
		)
		(fp_line
			(start -0.12065 -0.2794)
			(end 0.12065 -0.2794)
			(stroke
				(width 0.1)
				(type default)
			)
			(layer "F.Fab")
		)
		(fp_line
			(start -0.12065 -0.305054)
			(end -0.12065 -0.2794)
			(stroke
				(width 0.1)
				(type default)
			)
			(layer "F.Fab")
		)
		(fp_line
			(start -0.67945 0.3048)
			(end -0.67945 -0.305054)
			(stroke
				(width 0.1)
				(type default)
			)
			(layer "F.Fab")
		)
		(fp_line
			(start -0.67945 -0.305054)
			(end -0.12065 -0.305054)
			(stroke
				(width 0.1)
				(type default)
			)
			(layer "F.Fab")
		)
		(pad "1" smd circle
			(at -0.40005 0 180)
			(size 0 0)
			(layers "F.Cu" "F.Mask" "F.Paste")
			(net "SMB_BMC_SWB_EN")
		)
		(pad "2" smd circle
			(at 0.40005 0 180)
			(size 0 0)
			(layers "F.Cu" "F.Mask" "F.Paste")
			(net "SMB_BMC_SWB_EN_R")
		)
	)
	(footprint ""
		(layer "F.Cu")
		(at 378.002292 -383.88163 -90)
		(property "Reference" "C887"
			(at 0 0 270)
			(layer "F.SilkS")
			(hide yes)
			(effects
				(font
					(size 1.27 1.27)
				)
			)
		)
		(property "Value" ""
			(at 0 0 270)
			(layer "F.Fab")
			(effects
				(font
					(size 1.27 1.27)
				)
			)
		)
		(duplicate_pad_numbers_are_jumpers no)
		(fp_line
			(start -0.299974 0.150114)
			(end -0.299974 -0.150114)
			(stroke
				(width 0.1)
				(type default)
			)
			(layer "F.Fab")
		)
		(fp_line
			(start 0.299974 0.150114)
			(end -0.299974 0.150114)
			(stroke
				(width 0.1)
				(type default)
			)
			(layer "F.Fab")
		)
		(fp_line
			(start -0.299974 -0.150114)
			(end 0.299974 -0.150114)
			(stroke
				(width 0.1)
				(type default)
			)
			(layer "F.Fab")
		)
		(fp_line
			(start 0.299974 -0.150114)
			(end 0.299974 0.150114)
			(stroke
				(width 0.1)
				(type default)
			)
			(layer "F.Fab")
		)
		(pad "1" smd rect
			(at -0.2667 0 270)
			(size 0.3048 0.381)
			(layers "F.Cu" "F.Mask" "F.Paste")
			(net "P5E_CPU0_P3_TX_C_DP<7>")
		)
		(pad "2" smd rect
			(at 0.2667 0 270)
			(size 0.3048 0.381)
			(layers "F.Cu" "F.Mask" "F.Paste")
			(net "P5E_CPU0_P3_TX_DP<7>")
		)
	)
)
